# T6G (Grand Teton) — schematic netlist excerpt (pin names and nets, part order shuffled) for the footprints in the layout excerpt that follows; sources: Cadence DE-HDL packaged netlist, KiCad conversion of 04192023_DAF0TMB3IC0_F0TG_MB_C_brd_V02_OCP.brd

R6066  Q_RES  0 5% EMPTY  pkg 0402LF  page 151 : A = JTAG_SCM_TDI_R ; B = JTAG_SCM_TDI
R803  Q_RES  0 5% CHIP  pkg 0201LF  page 185 : A = SMB_RT_CPU1_P1_ROM_MUX_2D_SDA ; B = SMB_RT_CPU1_P1_ROM_MUX_2D_R_SDA
PR138  Q_RES  0 5% CHIP  pkg 0402LF  page 208 : A = PVDD11_S3_P0_VOS2 ; B = PVDD11_S3_P0

(kicad_pcb
	(version 20260206)
	(generator "pcbnew")
	(generator_version "10.0")
	(general
		(thickness 1.6)
		(legacy_teardrops no)
	)
	(paper "A4")
	(title_block
		(title "04192023_DAF0TMB3IC0_F0TG_MB_C_brd_V02_OCP.brd")
		(comment 1 "Grand Teton / footprints 7554-7556 of 8354")
	)
	(layers
		(0 "F.Cu" signal "TOP")
		(4 "In1.Cu" signal "GND")
		(6 "In2.Cu" signal "IN1")
		(8 "In3.Cu" signal "GND1")
		(10 "In4.Cu" signal "IN2")
		(12 "In5.Cu" signal "GND2")
		(14 "In6.Cu" signal "IN3")
		(16 "In7.Cu" signal "GND3")
		(18 "In8.Cu" signal "VCC")
		(20 "In9.Cu" signal "VCC1")
		(22 "In10.Cu" signal "GND4")
		(24 "In11.Cu" signal "IN4")
		(26 "In12.Cu" signal "GND5")
		(28 "In13.Cu" signal "IN5")
		(30 "In14.Cu" signal "GND6")
		(32 "In15.Cu" signal "IN6")
		(34 "In16.Cu" signal "GND7")
		(2 "B.Cu" signal "BOTTOM")
		(9 "F.Adhes" user "F.Adhesive")
		(11 "B.Adhes" user "B.Adhesive")
		(13 "F.Paste" user "Package Geometry/Pastemask Top")
		(15 "B.Paste" user "Package Geometry/Pastemask Bottom")
		(5 "F.SilkS" user "Ref Des/Silkscreen Top")
		(7 "B.SilkS" user "Ref Des/Silkscreen Bottom")
		(1 "F.Mask" user "Board Geometry/Soldermask Top")
		(3 "B.Mask" user "Board Geometry/Soldermask Bottom")
		(17 "Dwgs.User" user "User.Drawings")
		(19 "Cmts.User" user "User.Comments")
		(21 "Eco1.User" user "User.Eco1")
		(23 "Eco2.User" user "User.Eco2")
		(25 "Edge.Cuts" user "Board Geometry/Outline")
		(27 "Margin" user)
		(31 "F.CrtYd" user "Package Geometry/Place Bound Top")
		(29 "B.CrtYd" user "Package Geometry/Place Bound Bottom")
		(35 "F.Fab" user "Ref Des/Assembly Top")
		(33 "B.Fab" user "Ref Des/Assembly Bottom")
	)
	(footprint ""
		(layer "B.Cu")
		(at 130.657092 -49.502822 -90)
		(property "Reference" "R6066"
			(at 0 0 90)
			(layer "B.SilkS")
			(hide yes)
			(effects
				(font
					(size 1.27 1.27)
				)
				(justify mirror)
			)
		)
		(property "Value" ""
			(at 0 0 90)
			(layer "B.Fab")
			(effects
				(font
					(size 1.27 1.27)
				)
				(justify mirror)
			)
		)
		(duplicate_pad_numbers_are_jumpers no)
		(fp_line
			(start -0.7874 0.4064)
			(end 0.7874 0.4064)
			(stroke
				(width 0.1524)
				(type default)
			)
			(layer "B.SilkS")
		)
		(fp_line
			(start 0.7874 0.4064)
			(end 0.7874 -0.4064)
			(stroke
				(width 0.1524)
				(type default)
			)
			(layer "B.SilkS")
		)
		(fp_line
			(start -0.7874 -0.4064)
			(end -0.7874 0.4064)
			(stroke
				(width 0.1524)
				(type default)
			)
			(layer "B.SilkS")
		)
		(fp_line
			(start 0.7874 -0.4064)
			(end -0.7874 -0.4064)
			(stroke
				(width 0.1524)
				(type default)
			)
			(layer "B.SilkS")
		)
		(fp_line
			(start -0.67945 0.3048)
			(end -0.120396 0.3048)
			(stroke
				(width 0.1)
				(type default)
			)
			(layer "B.Fab")
		)
		(fp_line
			(start -0.120396 0.3048)
			(end -0.120396 0.2794)
			(stroke
				(width 0.1)
				(type default)
			)
			(layer "B.Fab")
		)
		(fp_line
			(start 0.12065 0.3048)
			(end 0.67945 0.3048)
			(stroke
				(width 0.1)
				(type default)
			)
			(layer "B.Fab")
		)
		(fp_line
			(start 0.67945 0.3048)
			(end 0.67945 -0.305054)
			(stroke
				(width 0.1)
				(type default)
			)
			(layer "B.Fab")
		)
		(fp_line
			(start -0.120396 0.2794)
			(end 0.12065 0.2794)
			(stroke
				(width 0.1)
				(type default)
			)
			(layer "B.Fab")
		)
		(fp_line
			(start 0.12065 0.2794)
			(end 0.12065 0.3048)
			(stroke
				(width 0.1)
				(type default)
			)
			(layer "B.Fab")
		)
		(fp_line
			(start -0.12065 -0.2794)
			(end -0.12065 -0.3048)
			(stroke
				(width 0.1)
				(type default)
			)
			(layer "B.Fab")
		)
		(fp_line
			(start 0.12065 -0.2794)
			(end -0.12065 -0.2794)
			(stroke
				(width 0.1)
				(type default)
			)
			(layer "B.Fab")
		)
		(fp_line
			(start -0.67945 -0.3048)
			(end -0.67945 0.3048)
			(stroke
				(width 0.1)
				(type default)
			)
			(layer "B.Fab")
		)
		(fp_line
			(start -0.12065 -0.3048)
			(end -0.67945 -0.3048)
			(stroke
				(width 0.1)
				(type default)
			)
			(layer "B.Fab")
		)
		(fp_line
			(start 0.12065 -0.305054)
			(end 0.12065 -0.2794)
			(stroke
				(width 0.1)
				(type default)
			)
			(layer "B.Fab")
		)
		(fp_line
			(start 0.67945 -0.305054)
			(end 0.12065 -0.305054)
			(stroke
				(width 0.1)
				(type default)
			)
			(layer "B.Fab")
		)
		(pad "1" smd rect
			(at 0.40005 0 270)
			(size 0.4572 0.508)
			(layers "B.Cu" "B.Mask" "B.Paste")
			(net "JTAG_SCM_TDI_R")
		)
		(pad "2" smd rect
			(at -0.40005 0 270)
			(size 0.4572 0.508)
			(layers "B.Cu" "B.Mask" "B.Paste")
			(net "JTAG_SCM_TDI")
		)
	)
	(footprint ""
		(layer "B.Cu")
		(at 238.633 -336.169 180)
		(property "Reference" "R803"
			(at 0 0 0)
			(layer "B.SilkS")
			(hide yes)
			(effects
				(font
					(size 1.27 1.27)
				)
				(justify mirror)
			)
		)
		(property "Value" ""
			(at 0 0 0)
			(layer "B.Fab")
			(effects
				(font
					(size 1.27 1.27)
				)
				(justify mirror)
			)
		)
		(duplicate_pad_numbers_are_jumpers no)
		(fp_line
			(start 0.32512 0.175006)
			(end 0.32512 -0.175006)
			(stroke
				(width 0.1)
				(type default)
			)
			(layer "B.Fab")
		)
		(fp_line
			(start 0.32512 -0.175006)
			(end -0.32512 -0.175006)
			(stroke
				(width 0.1)
				(type default)
			)
			(layer "B.Fab")
		)
		(fp_line
			(start -0.32512 0.175006)
			(end 0.32512 0.175006)
			(stroke
				(width 0.1)
				(type default)
			)
			(layer "B.Fab")
		)
		(fp_line
			(start -0.32512 -0.175006)
			(end -0.32512 0.175006)
			(stroke
				(width 0.1)
				(type default)
			)
			(layer "B.Fab")
		)
		(pad "1" smd rect
			(at 0.2667 0)
			(size 0.3048 0.381)
			(layers "B.Cu" "B.Mask" "B.Paste")
			(net "SMB_RT_CPU1_P1_ROM_MUX_2D_SDA")
		)
		(pad "2" smd rect
			(at -0.2667 0 180)
			(size 0.3048 0.381)
			(layers "B.Cu" "B.Mask" "B.Paste")
			(net "SMB_RT_CPU1_P1_ROM_MUX_2D_R_SDA")
		)
	)
	(footprint ""
		(layer "B.Cu")
		(at 428.309278 -353.80549 -90)
		(property "Reference" "PR138"
			(at 0 0 90)
			(layer "B.SilkS")
			(hide yes)
			(effects
				(font
					(size 1.27 1.27)
				)
				(justify mirror)
			)
		)
		(property "Value" ""
			(at 0 0 90)
			(layer "B.Fab")
			(effects
				(font
					(size 1.27 1.27)
				)
				(justify mirror)
			)
		)
		(duplicate_pad_numbers_are_jumpers no)
		(fp_line
			(start -0.7874 0.4064)
			(end 0.7874 0.4064)
			(stroke
				(width 0.1524)
				(type default)
			)
			(layer "B.SilkS")
		)
		(fp_line
			(start 0.7874 0.4064)
			(end 0.7874 -0.4064)
			(stroke
				(width 0.1524)
				(type default)
			)
			(layer "B.SilkS")
		)
		(fp_line
			(start -0.7874 -0.4064)
			(end -0.7874 0.4064)
			(stroke
				(width 0.1524)
				(type default)
			)
			(layer "B.SilkS")
		)
		(fp_line
			(start 0.7874 -0.4064)
			(end -0.7874 -0.4064)
			(stroke
				(width 0.1524)
				(type default)
			)
			(layer "B.SilkS")
		)
		(fp_line
			(start -0.67945 0.3048)
			(end -0.120396 0.3048)
			(stroke
				(width 0.1)
				(type default)
			)
			(layer "B.Fab")
		)
		(fp_line
			(start -0.120396 0.3048)
			(end -0.120396 0.2794)
			(stroke
				(width 0.1)
				(type default)
			)
			(layer "B.Fab")
		)
		(fp_line
			(start 0.12065 0.3048)
			(end 0.67945 0.3048)
			(stroke
				(width 0.1)
				(type default)
			)
			(layer "B.Fab")
		)
		(fp_line
			(start 0.67945 0.3048)
			(end 0.67945 -0.305054)
			(stroke
				(width 0.1)
				(type default)
			)
			(layer "B.Fab")
		)
		(fp_line
			(start -0.120396 0.2794)
			(end 0.12065 0.2794)
			(stroke
				(width 0.1)
				(type default)
			)
			(layer "B.Fab")
		)
		(fp_line
			(start 0.12065 0.2794)
			(end 0.12065 0.3048)
			(stroke
				(width 0.1)
				(type default)
			)
			(layer "B.Fab")
		)
		(fp_line
			(start -0.12065 -0.2794)
			(end -0.12065 -0.3048)
			(stroke
				(width 0.1)
				(type default)
			)
			(layer "B.Fab")
		)
		(fp_line
			(start 0.12065 -0.2794)
			(end -0.12065 -0.2794)
			(stroke
				(width 0.1)
				(type default)
			)
			(layer "B.Fab")
		)
		(fp_line
			(start -0.67945 -0.3048)
			(end -0.67945 0.3048)
			(stroke
				(width 0.1)
				(type default)
			)
			(layer "B.Fab")
		)
		(fp_line
			(start -0.12065 -0.3048)
			(end -0.67945 -0.3048)
			(stroke
				(width 0.1)
				(type default)
			)
			(layer "B.Fab")
		)
		(fp_line
			(start 0.12065 -0.305054)
			(end 0.12065 -0.2794)
			(stroke
				(width 0.1)
				(type default)
			)
			(layer "B.Fab")
		)
		(fp_line
			(start 0.67945 -0.305054)
			(end 0.12065 -0.305054)
			(stroke
				(width 0.1)
				(type default)
			)
			(layer "B.Fab")
		)
		(pad "1" smd circle
			(at 0.40005 0 90)
			(size 0 0)
			(layers "B.Cu" "B.Mask" "B.Paste")
			(net "PVDD11_S3_P0_VOS2")
		)
		(pad "2" smd circle
			(at -0.40005 0 90)
			(size 0 0)
			(layers "B.Cu" "B.Mask" "B.Paste")
			(net "PVDD11_S3_P0")
		)
	)
)
